# T6G (Grand Teton) — schematic netlist excerpt (pin names and nets, part order shuffled) for the footprints in the layout excerpt that follows; sources: Cadence DE-HDL packaged netlist, KiCad conversion of 04192023_DAF0TMB3IC0_F0TG_MB_C_brd_V02_OCP.brd

PC580  Q_CAP  2.2UF 10V 10% X6S  pkg C0402  page 198 : A = PVDDCR_SOC_P0_VCC2 ; B = GND
R6263  Q_RES  0 5% CHIP  pkg 0402LF  page 178 : A = USB_HUB2_TI_USB_DP_DN3_MRP_VDD12 ; B = P1V2_CPU0_USB2_DVDD12

(kicad_pcb
	(version 20260206)
	(generator "pcbnew")
	(generator_version "10.0")
	(general
		(thickness 1.6)
		(legacy_teardrops no)
	)
	(paper "A4")
	(title_block
		(title "04192023_DAF0TMB3IC0_F0TG_MB_C_brd_V02_OCP.brd")
		(comment 1 "Grand Teton / footprints 1426-1427 of 8354")
	)
	(layers
		(0 "F.Cu" signal "TOP")
		(4 "In1.Cu" signal "GND")
		(6 "In2.Cu" signal "IN1")
		(8 "In3.Cu" signal "GND1")
		(10 "In4.Cu" signal "IN2")
		(12 "In5.Cu" signal "GND2")
		(14 "In6.Cu" signal "IN3")
		(16 "In7.Cu" signal "GND3")
		(18 "In8.Cu" signal "VCC")
		(20 "In9.Cu" signal "VCC1")
		(22 "In10.Cu" signal "GND4")
		(24 "In11.Cu" signal "IN4")
		(26 "In12.Cu" signal "GND5")
		(28 "In13.Cu" signal "IN5")
		(30 "In14.Cu" signal "GND6")
		(32 "In15.Cu" signal "IN6")
		(34 "In16.Cu" signal "GND7")
		(2 "B.Cu" signal "BOTTOM")
		(9 "F.Adhes" user "F.Adhesive")
		(11 "B.Adhes" user "B.Adhesive")
		(13 "F.Paste" user "Package Geometry/Pastemask Top")
		(15 "B.Paste" user "Package Geometry/Pastemask Bottom")
		(5 "F.SilkS" user "Ref Des/Silkscreen Top")
		(7 "B.SilkS" user "Ref Des/Silkscreen Bottom")
		(1 "F.Mask" user "Board Geometry/Soldermask Top")
		(3 "B.Mask" user "Board Geometry/Soldermask Bottom")
		(17 "Dwgs.User" user "User.Drawings")
		(19 "Cmts.User" user "User.Comments")
		(21 "Eco1.User" user "User.Eco1")
		(23 "Eco2.User" user "User.Eco2")
		(25 "Edge.Cuts" user "Board Geometry/Outline")
		(27 "Margin" user)
		(31 "F.CrtYd" user "Package Geometry/Place Bound Top")
		(29 "B.CrtYd" user "Package Geometry/Place Bound Bottom")
		(35 "F.Fab" user "Ref Des/Assembly Top")
		(33 "B.Fab" user "Ref Des/Assembly Bottom")
	)
	(footprint ""
		(layer "F.Cu")
		(at 409.830778 -165.928548 -90)
		(property "Reference" "PC580"
			(at 0 0 270)
			(layer "F.SilkS")
			(hide yes)
			(effects
				(font
					(size 1.27 1.27)
				)
			)
		)
		(property "Value" ""
			(at 0 0 270)
			(layer "F.Fab")
			(effects
				(font
					(size 1.27 1.27)
				)
			)
		)
		(duplicate_pad_numbers_are_jumpers no)
		(fp_line
			(start -0.7874 0.4064)
			(end -0.7874 -0.4064)
			(stroke
				(width 0.1524)
				(type default)
			)
			(layer "F.SilkS")
		)
		(fp_line
			(start -0.289052 0.4064)
			(end -0.7874 0.4064)
			(stroke
				(width 0.1524)
				(type default)
			)
			(layer "F.SilkS")
		)
		(fp_line
			(start 0.7874 0.4064)
			(end 0.447548 0.4064)
			(stroke
				(width 0.1524)
				(type default)
			)
			(layer "F.SilkS")
		)
		(fp_line
			(start -0.7874 -0.4064)
			(end 0.7874 -0.4064)
			(stroke
				(width 0.1524)
				(type default)
			)
			(layer "F.SilkS")
		)
		(fp_line
			(start 0.7874 -0.4064)
			(end 0.7874 0.4064)
			(stroke
				(width 0.1524)
				(type default)
			)
			(layer "F.SilkS")
		)
		(fp_line
			(start -0.67945 0.3048)
			(end -0.67945 -0.305054)
			(stroke
				(width 0.1)
				(type default)
			)
			(layer "F.Fab")
		)
		(fp_line
			(start -0.12065 0.3048)
			(end -0.67945 0.3048)
			(stroke
				(width 0.1)
				(type default)
			)
			(layer "F.Fab")
		)
		(fp_line
			(start 0.120396 0.3048)
			(end 0.120396 0.2794)
			(stroke
				(width 0.1)
				(type default)
			)
			(layer "F.Fab")
		)
		(fp_line
			(start 0.67945 0.3048)
			(end 0.120396 0.3048)
			(stroke
				(width 0.1)
				(type default)
			)
			(layer "F.Fab")
		)
		(fp_line
			(start -0.12065 0.2794)
			(end -0.12065 0.3048)
			(stroke
				(width 0.1)
				(type default)
			)
			(layer "F.Fab")
		)
		(fp_line
			(start 0.120396 0.2794)
			(end -0.12065 0.2794)
			(stroke
				(width 0.1)
				(type default)
			)
			(layer "F.Fab")
		)
		(fp_line
			(start -0.12065 -0.2794)
			(end 0.12065 -0.2794)
			(stroke
				(width 0.1)
				(type default)
			)
			(layer "F.Fab")
		)
		(fp_line
			(start 0.12065 -0.2794)
			(end 0.12065 -0.3048)
			(stroke
				(width 0.1)
				(type default)
			)
			(layer "F.Fab")
		)
		(fp_line
			(start 0.12065 -0.3048)
			(end 0.67945 -0.3048)
			(stroke
				(width 0.1)
				(type default)
			)
			(layer "F.Fab")
		)
		(fp_line
			(start 0.67945 -0.3048)
			(end 0.67945 0.3048)
			(stroke
				(width 0.1)
				(type default)
			)
			(layer "F.Fab")
		)
		(fp_line
			(start -0.67945 -0.305054)
			(end -0.12065 -0.305054)
			(stroke
				(width 0.1)
				(type default)
			)
			(layer "F.Fab")
		)
		(fp_line
			(start -0.12065 -0.305054)
			(end -0.12065 -0.2794)
			(stroke
				(width 0.1)
				(type default)
			)
			(layer "F.Fab")
		)
		(pad "1" smd circle
			(at -0.40005 0 270)
			(size 0 0)
			(layers "F.Cu" "F.Mask" "F.Paste")
			(net "PVDDCR_SOC_P0_VCC2")
		)
		(pad "2" smd circle
			(at 0.40005 0 270)
			(size 0 0)
			(layers "F.Cu" "F.Mask" "F.Paste")
			(net "GND")
		)
	)
	(footprint ""
		(layer "F.Cu")
		(at 120.68175 -24.275796)
		(property "Reference" "R6263"
			(at 0 0 0)
			(layer "F.SilkS")
			(hide yes)
			(effects
				(font
					(size 1.27 1.27)
				)
			)
		)
		(property "Value" ""
			(at 0 0 0)
			(layer "F.Fab")
			(effects
				(font
					(size 1.27 1.27)
				)
			)
		)
		(duplicate_pad_numbers_are_jumpers no)
		(fp_line
			(start -0.7874 -0.4064)
			(end 0.7874 -0.4064)
			(stroke
				(width 0.1524)
				(type default)
			)
			(layer "F.SilkS")
		)
		(fp_line
			(start -0.7874 0.4064)
			(end -0.7874 -0.4064)
			(stroke
				(width 0.1524)
				(type default)
			)
			(layer "F.SilkS")
		)
		(fp_line
			(start 0.7874 -0.4064)
			(end 0.7874 0.4064)
			(stroke
				(width 0.1524)
				(type default)
			)
			(layer "F.SilkS")
		)
		(fp_line
			(start 0.7874 0.4064)
			(end -0.7874 0.4064)
			(stroke
				(width 0.1524)
				(type default)
			)
			(layer "F.SilkS")
		)
		(fp_line
			(start -0.67945 -0.305054)
			(end -0.12065 -0.305054)
			(stroke
				(width 0.1)
				(type default)
			)
			(layer "F.Fab")
		)
		(fp_line
			(start -0.67945 0.3048)
			(end -0.67945 -0.305054)
			(stroke
				(width 0.1)
				(type default)
			)
			(layer "F.Fab")
		)
		(fp_line
			(start -0.12065 -0.305054)
			(end -0.12065 -0.2794)
			(stroke
				(width 0.1)
				(type default)
			)
			(layer "F.Fab")
		)
		(fp_line
			(start -0.12065 -0.2794)
			(end 0.12065 -0.2794)
			(stroke
				(width 0.1)
				(type default)
			)
			(layer "F.Fab")
		)
		(fp_line
			(start -0.12065 0.2794)
			(end -0.12065 0.3048)
			(stroke
				(width 0.1)
				(type default)
			)
			(layer "F.Fab")
		)
		(fp_line
			(start -0.12065 0.3048)
			(end -0.67945 0.3048)
			(stroke
				(width 0.1)
				(type default)
			)
			(layer "F.Fab")
		)
		(fp_line
			(start 0.120396 0.2794)
			(end -0.12065 0.2794)
			(stroke
				(width 0.1)
				(type default)
			)
			(layer "F.Fab")
		)
		(fp_line
			(start 0.120396 0.3048)
			(end 0.120396 0.2794)
			(stroke
				(width 0.1)
				(type default)
			)
			(layer "F.Fab")
		)
		(fp_line
			(start 0.12065 -0.3048)
			(end 0.67945 -0.3048)
			(stroke
				(width 0.1)
				(type default)
			)
			(layer "F.Fab")
		)
		(fp_line
			(start 0.12065 -0.2794)
			(end 0.12065 -0.3048)
			(stroke
				(width 0.1)
				(type default)
			)
			(layer "F.Fab")
		)
		(fp_line
			(start 0.67945 -0.3048)
			(end 0.67945 0.3048)
			(stroke
				(width 0.1)
				(type default)
			)
			(layer "F.Fab")
		)
		(fp_line
			(start 0.67945 0.3048)
			(end 0.120396 0.3048)
			(stroke
				(width 0.1)
				(type default)
			)
			(layer "F.Fab")
		)
		(pad "1" smd circle
			(at -0.40005 0)
			(size 0 0)
			(layers "F.Cu" "F.Mask" "F.Paste")
			(net "USB_HUB2_TI_USB_DP_DN3_MRP_VDD12")
		)
		(pad "2" smd circle
			(at 0.40005 0)
			(size 0 0)
			(layers "F.Cu" "F.Mask" "F.Paste")
			(net "P1V2_CPU0_USB2_DVDD12")
		)
	)
)
